# S9S_MB_2U (Grand Teton) — schematic netlist excerpt (pin names and nets, part order shuffled) for the footprints in the layout excerpt that follows; sources: Cadence DE-HDL packaged netlist, KiCad conversion of 03242023_DA0F0TMBIJ0_F0T_Motherboard_J_brd_V01_OCP.brd

C2267  Q_CAP  1000PF 50V 5% EMPTY  pkg 0402  page 146 : A = GPU_3V3IO_RSVD3_FFU_ISO ; B = GND
PC440  Q_CAP  2.2UF 10V 10% X6S  pkg C0402  page 293 : A = PVCCINFAON_CPU1_VDD1 ; B = GND

(kicad_pcb
	(version 20260206)
	(generator "pcbnew")
	(generator_version "10.0")
	(general
		(thickness 1.6)
		(legacy_teardrops no)
	)
	(paper "A4")
	(title_block
		(title "03242023_DA0F0TMBIJ0_F0T_Motherboard_J_brd_V01_OCP.brd")
		(comment 1 "Grand Teton / footprints 79-80 of 6105")
	)
	(layers
		(0 "F.Cu" signal "TOP")
		(4 "In1.Cu" signal "GND")
		(6 "In2.Cu" signal "IN1")
		(8 "In3.Cu" signal "GND1")
		(10 "In4.Cu" signal "IN2")
		(12 "In5.Cu" signal "GND2")
		(14 "In6.Cu" signal "IN3")
		(16 "In7.Cu" signal "GND3")
		(18 "In8.Cu" signal "VCC")
		(20 "In9.Cu" signal "VCC1")
		(22 "In10.Cu" signal "GND4")
		(24 "In11.Cu" signal "IN4")
		(26 "In12.Cu" signal "GND5")
		(28 "In13.Cu" signal "IN5")
		(30 "In14.Cu" signal "GND6")
		(32 "In15.Cu" signal "IN6")
		(34 "In16.Cu" signal "GND7")
		(2 "B.Cu" signal "BOTTOM")
		(9 "F.Adhes" user "F.Adhesive")
		(11 "B.Adhes" user "B.Adhesive")
		(13 "F.Paste" user "Package Geometry/Pastemask Top")
		(15 "B.Paste" user "Package Geometry/Pastemask Bottom")
		(5 "F.SilkS" user "Ref Des/Silkscreen Top")
		(7 "B.SilkS" user "Ref Des/Silkscreen Bottom")
		(1 "F.Mask" user "Board Geometry/Soldermask Top")
		(3 "B.Mask" user "Board Geometry/Soldermask Bottom")
		(17 "Dwgs.User" user "User.Drawings")
		(19 "Cmts.User" user "User.Comments")
		(21 "Eco1.User" user "User.Eco1")
		(23 "Eco2.User" user "User.Eco2")
		(25 "Edge.Cuts" user "Board Geometry/Outline")
		(27 "Margin" user)
		(31 "F.CrtYd" user "Package Geometry/Place Bound Top")
		(29 "B.CrtYd" user "Package Geometry/Place Bound Bottom")
		(35 "F.Fab" user "Ref Des/Assembly Top")
		(33 "B.Fab" user "Ref Des/Assembly Bottom")
	)
	(footprint ""
		(layer "F.Cu")
		(at 304.09896 -430.65827 -90)
		(property "Reference" "C2267"
			(at 0 0 270)
			(layer "F.SilkS")
			(hide yes)
			(effects
				(font
					(size 1.27 1.27)
				)
			)
		)
		(property "Value" ""
			(at 0 0 270)
			(layer "F.Fab")
			(effects
				(font
					(size 1.27 1.27)
				)
			)
		)
		(duplicate_pad_numbers_are_jumpers no)
		(fp_line
			(start -0.7874 0.4064)
			(end -0.7874 -0.4064)
			(stroke
				(width 0.1524)
				(type default)
			)
			(layer "F.SilkS")
		)
		(fp_line
			(start 0.7874 0.4064)
			(end -0.7874 0.4064)
			(stroke
				(width 0.1524)
				(type default)
			)
			(layer "F.SilkS")
		)
		(fp_line
			(start -0.7874 -0.4064)
			(end 0.7874 -0.4064)
			(stroke
				(width 0.1524)
				(type default)
			)
			(layer "F.SilkS")
		)
		(fp_line
			(start 0.7874 -0.4064)
			(end 0.7874 0.4064)
			(stroke
				(width 0.1524)
				(type default)
			)
			(layer "F.SilkS")
		)
		(fp_line
			(start -0.67945 0.3048)
			(end -0.67945 -0.305054)
			(stroke
				(width 0.1)
				(type default)
			)
			(layer "F.Fab")
		)
		(fp_line
			(start -0.12065 0.3048)
			(end -0.67945 0.3048)
			(stroke
				(width 0.1)
				(type default)
			)
			(layer "F.Fab")
		)
		(fp_line
			(start 0.120396 0.3048)
			(end 0.120396 0.2794)
			(stroke
				(width 0.1)
				(type default)
			)
			(layer "F.Fab")
		)
		(fp_line
			(start 0.67945 0.3048)
			(end 0.120396 0.3048)
			(stroke
				(width 0.1)
				(type default)
			)
			(layer "F.Fab")
		)
		(fp_line
			(start -0.12065 0.2794)
			(end -0.12065 0.3048)
			(stroke
				(width 0.1)
				(type default)
			)
			(layer "F.Fab")
		)
		(fp_line
			(start 0.120396 0.2794)
			(end -0.12065 0.2794)
			(stroke
				(width 0.1)
				(type default)
			)
			(layer "F.Fab")
		)
		(fp_line
			(start -0.12065 -0.2794)
			(end 0.12065 -0.2794)
			(stroke
				(width 0.1)
				(type default)
			)
			(layer "F.Fab")
		)
		(fp_line
			(start 0.12065 -0.2794)
			(end 0.12065 -0.3048)
			(stroke
				(width 0.1)
				(type default)
			)
			(layer "F.Fab")
		)
		(fp_line
			(start 0.12065 -0.3048)
			(end 0.67945 -0.3048)
			(stroke
				(width 0.1)
				(type default)
			)
			(layer "F.Fab")
		)
		(fp_line
			(start 0.67945 -0.3048)
			(end 0.67945 0.3048)
			(stroke
				(width 0.1)
				(type default)
			)
			(layer "F.Fab")
		)
		(fp_line
			(start -0.67945 -0.305054)
			(end -0.12065 -0.305054)
			(stroke
				(width 0.1)
				(type default)
			)
			(layer "F.Fab")
		)
		(fp_line
			(start -0.12065 -0.305054)
			(end -0.12065 -0.2794)
			(stroke
				(width 0.1)
				(type default)
			)
			(layer "F.Fab")
		)
		(pad "1" smd circle
			(at -0.40005 0 270)
			(size 0 0)
			(layers "F.Cu" "F.Mask" "F.Paste")
			(net "GPU_3V3IO_RSVD3_FFU_ISO")
		)
		(pad "2" smd circle
			(at 0.40005 0 270)
			(size 0 0)
			(layers "F.Cu" "F.Mask" "F.Paste")
			(net "GND")
		)
	)
	(footprint ""
		(layer "F.Cu")
		(at 52.423314 -152.903174 180)
		(property "Reference" "PC440"
			(at 0 0 180)
			(layer "F.SilkS")
			(hide yes)
			(effects
				(font
					(size 1.27 1.27)
				)
			)
		)
		(property "Value" ""
			(at 0 0 180)
			(layer "F.Fab")
			(effects
				(font
					(size 1.27 1.27)
				)
			)
		)
		(duplicate_pad_numbers_are_jumpers no)
		(fp_line
			(start 0.7874 0.4064)
			(end -0.7874 0.4064)
			(stroke
				(width 0.1524)
				(type default)
			)
			(layer "F.SilkS")
		)
		(fp_line
			(start 0.7874 -0.4064)
			(end 0.7874 0.4064)
			(stroke
				(width 0.1524)
				(type default)
			)
			(layer "F.SilkS")
		)
		(fp_line
			(start -0.7874 0.4064)
			(end -0.7874 -0.4064)
			(stroke
				(width 0.1524)
				(type default)
			)
			(layer "F.SilkS")
		)
		(fp_line
			(start -0.7874 -0.4064)
			(end 0.7874 -0.4064)
			(stroke
				(width 0.1524)
				(type default)
			)
			(layer "F.SilkS")
		)
		(fp_line
			(start 0.67945 0.3048)
			(end 0.120396 0.3048)
			(stroke
				(width 0.1)
				(type default)
			)
			(layer "F.Fab")
		)
		(fp_line
			(start 0.67945 -0.3048)
			(end 0.67945 0.3048)
			(stroke
				(width 0.1)
				(type default)
			)
			(layer "F.Fab")
		)
		(fp_line
			(start 0.12065 -0.2794)
			(end 0.12065 -0.3048)
			(stroke
				(width 0.1)
				(type default)
			)
			(layer "F.Fab")
		)
		(fp_line
			(start 0.12065 -0.3048)
			(end 0.67945 -0.3048)
			(stroke
				(width 0.1)
				(type default)
			)
			(layer "F.Fab")
		)
		(fp_line
			(start 0.120396 0.3048)
			(end 0.120396 0.2794)
			(stroke
				(width 0.1)
				(type default)
			)
			(layer "F.Fab")
		)
		(fp_line
			(start 0.120396 0.2794)
			(end -0.12065 0.2794)
			(stroke
				(width 0.1)
				(type default)
			)
			(layer "F.Fab")
		)
		(fp_line
			(start -0.12065 0.3048)
			(end -0.67945 0.3048)
			(stroke
				(width 0.1)
				(type default)
			)
			(layer "F.Fab")
		)
		(fp_line
			(start -0.12065 0.2794)
			(end -0.12065 0.3048)
			(stroke
				(width 0.1)
				(type default)
			)
			(layer "F.Fab")
		)
		(fp_line
			(start -0.12065 -0.2794)
			(end 0.12065 -0.2794)
			(stroke
				(width 0.1)
				(type default)
			)
			(layer "F.Fab")
		)
		(fp_line
			(start -0.12065 -0.305054)
			(end -0.12065 -0.2794)
			(stroke
				(width 0.1)
				(type default)
			)
			(layer "F.Fab")
		)
		(fp_line
			(start -0.67945 0.3048)
			(end -0.67945 -0.305054)
			(stroke
				(width 0.1)
				(type default)
			)
			(layer "F.Fab")
		)
		(fp_line
			(start -0.67945 -0.305054)
			(end -0.12065 -0.305054)
			(stroke
				(width 0.1)
				(type default)
			)
			(layer "F.Fab")
		)
		(pad "1" smd circle
			(at -0.40005 0 180)
			(size 0 0)
			(layers "F.Cu" "F.Mask" "F.Paste")
			(net "PVCCINFAON_CPU1_VDD1")
		)
		(pad "2" smd circle
			(at 0.40005 0 180)
			(size 0 0)
			(layers "F.Cu" "F.Mask" "F.Paste")
			(net "GND")
		)
	)
)
